# S9S_MB_2U (Grand Teton) — schematic netlist excerpt (pin names and nets, part order shuffled) for the footprints in the layout excerpt that follows; sources: Cadence DE-HDL packaged netlist, KiCad conversion of 03242023_DA0F0TMBIJ0_F0T_Motherboard_J_brd_V01_OCP.brd

C1997  Q_CAP  0.1UF 25V 10% X7R  pkg 0402  page 194 : A = P3V3_AUX ; B = GND
R4597  Q_RES  10K 1% EMPTY  pkg 0402LF  page 195 : A = P3V3_AUX ; B = FM_BOARD_BMC_SKU_ID2

(kicad_pcb
	(version 20260206)
	(generator "pcbnew")
	(generator_version "10.0")
	(general
		(thickness 1.6)
		(legacy_teardrops no)
	)
	(paper "A4")
	(title_block
		(title "03242023_DA0F0TMBIJ0_F0T_Motherboard_J_brd_V01_OCP.brd")
		(comment 1 "Grand Teton / footprints 3222-3223 of 6105")
	)
	(layers
		(0 "F.Cu" signal "TOP")
		(4 "In1.Cu" signal "GND")
		(6 "In2.Cu" signal "IN1")
		(8 "In3.Cu" signal "GND1")
		(10 "In4.Cu" signal "IN2")
		(12 "In5.Cu" signal "GND2")
		(14 "In6.Cu" signal "IN3")
		(16 "In7.Cu" signal "GND3")
		(18 "In8.Cu" signal "VCC")
		(20 "In9.Cu" signal "VCC1")
		(22 "In10.Cu" signal "GND4")
		(24 "In11.Cu" signal "IN4")
		(26 "In12.Cu" signal "GND5")
		(28 "In13.Cu" signal "IN5")
		(30 "In14.Cu" signal "GND6")
		(32 "In15.Cu" signal "IN6")
		(34 "In16.Cu" signal "GND7")
		(2 "B.Cu" signal "BOTTOM")
		(9 "F.Adhes" user "F.Adhesive")
		(11 "B.Adhes" user "B.Adhesive")
		(13 "F.Paste" user "Package Geometry/Pastemask Top")
		(15 "B.Paste" user "Package Geometry/Pastemask Bottom")
		(5 "F.SilkS" user "Ref Des/Silkscreen Top")
		(7 "B.SilkS" user "Ref Des/Silkscreen Bottom")
		(1 "F.Mask" user "Board Geometry/Soldermask Top")
		(3 "B.Mask" user "Board Geometry/Soldermask Bottom")
		(17 "Dwgs.User" user "User.Drawings")
		(19 "Cmts.User" user "User.Comments")
		(21 "Eco1.User" user "User.Eco1")
		(23 "Eco2.User" user "User.Eco2")
		(25 "Edge.Cuts" user "Board Geometry/Outline")
		(27 "Margin" user)
		(31 "F.CrtYd" user "Package Geometry/Place Bound Top")
		(29 "B.CrtYd" user "Package Geometry/Place Bound Bottom")
		(35 "F.Fab" user "Ref Des/Assembly Top")
		(33 "B.Fab" user "Ref Des/Assembly Bottom")
	)
	(footprint ""
		(layer "F.Cu")
		(at 174.1424 -93.538548 90)
		(property "Reference" "R4597"
			(at 0 0 90)
			(layer "F.SilkS")
			(hide yes)
			(effects
				(font
					(size 1.27 1.27)
				)
			)
		)
		(property "Value" ""
			(at 0 0 90)
			(layer "F.Fab")
			(effects
				(font
					(size 1.27 1.27)
				)
			)
		)
		(duplicate_pad_numbers_are_jumpers no)
		(fp_line
			(start 0.7874 -0.4064)
			(end 0.7874 0.4064)
			(stroke
				(width 0.1524)
				(type default)
			)
			(layer "F.SilkS")
		)
		(fp_line
			(start -0.7874 -0.4064)
			(end 0.7874 -0.4064)
			(stroke
				(width 0.1524)
				(type default)
			)
			(layer "F.SilkS")
		)
		(fp_line
			(start 0.7874 0.4064)
			(end -0.7874 0.4064)
			(stroke
				(width 0.1524)
				(type default)
			)
			(layer "F.SilkS")
		)
		(fp_line
			(start -0.7874 0.4064)
			(end -0.7874 -0.4064)
			(stroke
				(width 0.1524)
				(type default)
			)
			(layer "F.SilkS")
		)
		(fp_line
			(start -0.12065 -0.305054)
			(end -0.12065 -0.2794)
			(stroke
				(width 0.1)
				(type default)
			)
			(layer "F.Fab")
		)
		(fp_line
			(start -0.67945 -0.305054)
			(end -0.12065 -0.305054)
			(stroke
				(width 0.1)
				(type default)
			)
			(layer "F.Fab")
		)
		(fp_line
			(start 0.67945 -0.3048)
			(end 0.67945 0.3048)
			(stroke
				(width 0.1)
				(type default)
			)
			(layer "F.Fab")
		)
		(fp_line
			(start 0.12065 -0.3048)
			(end 0.67945 -0.3048)
			(stroke
				(width 0.1)
				(type default)
			)
			(layer "F.Fab")
		)
		(fp_line
			(start 0.12065 -0.2794)
			(end 0.12065 -0.3048)
			(stroke
				(width 0.1)
				(type default)
			)
			(layer "F.Fab")
		)
		(fp_line
			(start -0.12065 -0.2794)
			(end 0.12065 -0.2794)
			(stroke
				(width 0.1)
				(type default)
			)
			(layer "F.Fab")
		)
		(fp_line
			(start 0.120396 0.2794)
			(end -0.12065 0.2794)
			(stroke
				(width 0.1)
				(type default)
			)
			(layer "F.Fab")
		)
		(fp_line
			(start -0.12065 0.2794)
			(end -0.12065 0.3048)
			(stroke
				(width 0.1)
				(type default)
			)
			(layer "F.Fab")
		)
		(fp_line
			(start 0.67945 0.3048)
			(end 0.120396 0.3048)
			(stroke
				(width 0.1)
				(type default)
			)
			(layer "F.Fab")
		)
		(fp_line
			(start 0.120396 0.3048)
			(end 0.120396 0.2794)
			(stroke
				(width 0.1)
				(type default)
			)
			(layer "F.Fab")
		)
		(fp_line
			(start -0.12065 0.3048)
			(end -0.67945 0.3048)
			(stroke
				(width 0.1)
				(type default)
			)
			(layer "F.Fab")
		)
		(fp_line
			(start -0.67945 0.3048)
			(end -0.67945 -0.305054)
			(stroke
				(width 0.1)
				(type default)
			)
			(layer "F.Fab")
		)
		(pad "1" smd rect
			(at -0.40005 0 270)
			(size 0.4572 0.508)
			(layers "F.Cu" "F.Mask" "F.Paste")
			(net "P3V3_AUX")
		)
		(pad "2" smd rect
			(at 0.40005 0 270)
			(size 0.4572 0.508)
			(layers "F.Cu" "F.Mask" "F.Paste")
			(net "FM_BOARD_BMC_SKU_ID2")
		)
	)
	(footprint ""
		(layer "F.Cu")
		(at 215.98128 -41.341548)
		(property "Reference" "C1997"
			(at 0 0 0)
			(layer "F.SilkS")
			(hide yes)
			(effects
				(font
					(size 1.27 1.27)
				)
			)
		)
		(property "Value" ""
			(at 0 0 0)
			(layer "F.Fab")
			(effects
				(font
					(size 1.27 1.27)
				)
			)
		)
		(duplicate_pad_numbers_are_jumpers no)
		(fp_line
			(start -0.7874 -0.4064)
			(end 0.7874 -0.4064)
			(stroke
				(width 0.1524)
				(type default)
			)
			(layer "F.SilkS")
		)
		(fp_line
			(start -0.7874 0.4064)
			(end -0.7874 -0.4064)
			(stroke
				(width 0.1524)
				(type default)
			)
			(layer "F.SilkS")
		)
		(fp_line
			(start 0.7874 -0.4064)
			(end 0.7874 0.4064)
			(stroke
				(width 0.1524)
				(type default)
			)
			(layer "F.SilkS")
		)
		(fp_line
			(start 0.7874 0.4064)
			(end -0.7874 0.4064)
			(stroke
				(width 0.1524)
				(type default)
			)
			(layer "F.SilkS")
		)
		(fp_line
			(start -0.67945 -0.305054)
			(end -0.12065 -0.305054)
			(stroke
				(width 0.1)
				(type default)
			)
			(layer "F.Fab")
		)
		(fp_line
			(start -0.67945 0.3048)
			(end -0.67945 -0.305054)
			(stroke
				(width 0.1)
				(type default)
			)
			(layer "F.Fab")
		)
		(fp_line
			(start -0.12065 -0.305054)
			(end -0.12065 -0.2794)
			(stroke
				(width 0.1)
				(type default)
			)
			(layer "F.Fab")
		)
		(fp_line
			(start -0.12065 -0.2794)
			(end 0.12065 -0.2794)
			(stroke
				(width 0.1)
				(type default)
			)
			(layer "F.Fab")
		)
		(fp_line
			(start -0.12065 0.2794)
			(end -0.12065 0.3048)
			(stroke
				(width 0.1)
				(type default)
			)
			(layer "F.Fab")
		)
		(fp_line
			(start -0.12065 0.3048)
			(end -0.67945 0.3048)
			(stroke
				(width 0.1)
				(type default)
			)
			(layer "F.Fab")
		)
		(fp_line
			(start 0.120396 0.2794)
			(end -0.12065 0.2794)
			(stroke
				(width 0.1)
				(type default)
			)
			(layer "F.Fab")
		)
		(fp_line
			(start 0.120396 0.3048)
			(end 0.120396 0.2794)
			(stroke
				(width 0.1)
				(type default)
			)
			(layer "F.Fab")
		)
		(fp_line
			(start 0.12065 -0.3048)
			(end 0.67945 -0.3048)
			(stroke
				(width 0.1)
				(type default)
			)
			(layer "F.Fab")
		)
		(fp_line
			(start 0.12065 -0.2794)
			(end 0.12065 -0.3048)
			(stroke
				(width 0.1)
				(type default)
			)
			(layer "F.Fab")
		)
		(fp_line
			(start 0.67945 -0.3048)
			(end 0.67945 0.3048)
			(stroke
				(width 0.1)
				(type default)
			)
			(layer "F.Fab")
		)
		(fp_line
			(start 0.67945 0.3048)
			(end 0.120396 0.3048)
			(stroke
				(width 0.1)
				(type default)
			)
			(layer "F.Fab")
		)
		(pad "1" smd circle
			(at -0.40005 0)
			(size 0 0)
			(layers "F.Cu" "F.Mask" "F.Paste")
			(net "P3V3_AUX")
		)
		(pad "2" smd circle
			(at 0.40005 0)
			(size 0 0)
			(layers "F.Cu" "F.Mask" "F.Paste")
			(net "GND")
		)
	)
)
